FILE_TYPE = MACRO_DRAWING;
SET COLOR_WIRE YELLOW;
SET COLOR_PROP ORANGE;
SET COLOR_DOT WHITE;
SET COLOR_ARC YELLOW;
SET COLOR_BODY GREEN;
SET COLOR_NOTE PURPLE;
SET PROP_DISPLAY VALUE;
SET PAGE_NUMBER P74;
FORCEADD Q_CAP..1
(-8550 3000);
FORCEPROP 1 LAST LOCATION C2661
J 0
(-8500 3100);
DISPLAY 0.489362 (-8500 3100);
PAINT SKYBLUE (-8500 3100);
FORCEPROP 2 LAST $SEC 1
J 0
(-8500 3200);
DISPLAY 0.680851 (-8500 3200);
PAINT MONO (-8500 3200);
DISPLAY INVISIBLE (-8500 3200);
FORCEPROP 2 LAST CDS_SEC 1
J 0
(-8500 3200);
DISPLAY 1.021277 (-8500 3200);
DISPLAY INVISIBLE (-8500 3200);
FORCEPROP 1 LASTPIN (-8550 3100) $PN 1
J 0
(-8540 3080);
DISPLAY 0.489362 (-8540 3080);
FORCEPROP 1 LASTPIN (-8550 2900) $PN 2
J 0
(-8540 2880);
DISPLAY 0.489362 (-8540 2880);
FORCEPROP 1 LAST PACK_TYPE C0402
J 0
(-8500 2800);
DISPLAY 0.489362 (-8500 2800);
PAINT SKYBLUE (-8500 2800);
FORCEPROP 1 LAST VOLTAGE 4V
J 0
(-8500 3000);
DISPLAY 0.489362 (-8500 3000);
PAINT SKYBLUE (-8500 3000);
FORCEPROP 1 LAST VALUE 22UF
J 0
(-8500 3050);
DISPLAY 0.489362 (-8500 3050);
PAINT SKYBLUE (-8500 3050);
FORCEPROP 1 LAST TOLERANCE 20%
J 0
(-8500 2950);
DISPLAY 0.489362 (-8500 2950);
PAINT SKYBLUE (-8500 2950);
FORCEPROP 1 LAST MATERIAL X6S
J 0
(-8500 2900);
DISPLAY 0.489362 (-8500 2900);
PAINT SKYBLUE (-8500 2900);
FORCEPROP 2 LAST CDS_LIB pure_quanta
J 0
(-8550 3000);
PAINT MONO (-8550 3000);
DISPLAY INVISIBLE (-8550 3000);
FORCEPROP 1 LAST PATH I1
J 0
(-8500 3150);
DISPLAY 0.978723 (-8500 3150);
PAINT WHITE (-8500 3150);
DISPLAY INVISIBLE (-8500 3150);
FORCEPROP 1 LAST PART_NUMBER CH622KMEB02
J 0
(-8500 2850);
DISPLAY 0.489362 (-8500 2850);
PAINT SKYBLUE (-8500 2850);
DISPLAY INVISIBLE (-8500 2850);
FORCEADD Q_CAP..1
(-7650 3775);
FORCEPROP 1 LAST LOCATION C2665
J 0
(-7600 3875);
DISPLAY 0.489362 (-7600 3875);
PAINT SKYBLUE (-7600 3875);
FORCEPROP 2 LAST $SEC 1
J 0
(-7600 3975);
DISPLAY 0.680851 (-7600 3975);
PAINT MONO (-7600 3975);
DISPLAY INVISIBLE (-7600 3975);
FORCEPROP 2 LAST CDS_SEC 1
J 0
(-7600 3975);
DISPLAY 1.021277 (-7600 3975);
DISPLAY INVISIBLE (-7600 3975);
FORCEPROP 1 LASTPIN (-7650 3875) $PN 1
J 0
(-7640 3855);
DISPLAY 0.489362 (-7640 3855);
FORCEPROP 1 LASTPIN (-7650 3675) $PN 2
J 0
(-7640 3655);
DISPLAY 0.489362 (-7640 3655);
FORCEPROP 1 LAST PACK_TYPE C0402
J 0
(-7600 3575);
DISPLAY 0.489362 (-7600 3575);
PAINT SKYBLUE (-7600 3575);
FORCEPROP 1 LAST VOLTAGE 4V
J 0
(-7600 3775);
DISPLAY 0.489362 (-7600 3775);
PAINT SKYBLUE (-7600 3775);
FORCEPROP 1 LAST VALUE 22UF
J 0
(-7600 3825);
DISPLAY 0.489362 (-7600 3825);
PAINT SKYBLUE (-7600 3825);
FORCEPROP 1 LAST TOLERANCE 20%
J 0
(-7600 3725);
DISPLAY 0.489362 (-7600 3725);
PAINT SKYBLUE (-7600 3725);
FORCEPROP 1 LAST MATERIAL X6S
J 0
(-7600 3675);
DISPLAY 0.489362 (-7600 3675);
PAINT SKYBLUE (-7600 3675);
FORCEPROP 2 LAST CDS_LIB pure_quanta
J 0
(-7650 3775);
PAINT MONO (-7650 3775);
DISPLAY INVISIBLE (-7650 3775);
FORCEPROP 1 LAST PATH I10
J 0
(-7600 3925);
DISPLAY 0.978723 (-7600 3925);
PAINT WHITE (-7600 3925);
DISPLAY INVISIBLE (-7600 3925);
FORCEPROP 1 LAST PART_NUMBER CH622KMEB02
J 0
(-7600 3625);
DISPLAY 0.489362 (-7600 3625);
PAINT SKYBLUE (-7600 3625);
DISPLAY INVISIBLE (-7600 3625);
FORCEADD Q_CAP..1
(-7200 3775);
FORCEPROP 1 LAST LOCATION C2667
J 0
(-7150 3875);
DISPLAY 0.489362 (-7150 3875);
PAINT SKYBLUE (-7150 3875);
FORCEPROP 2 LAST $SEC 1
J 0
(-7150 3975);
DISPLAY 0.680851 (-7150 3975);
PAINT MONO (-7150 3975);
DISPLAY INVISIBLE (-7150 3975);
FORCEPROP 2 LAST CDS_SEC 1
J 0
(-7150 3975);
DISPLAY 1.021277 (-7150 3975);
DISPLAY INVISIBLE (-7150 3975);
FORCEPROP 1 LASTPIN (-7200 3875) $PN 1
J 0
(-7190 3855);
DISPLAY 0.489362 (-7190 3855);
FORCEPROP 1 LASTPIN (-7200 3675) $PN 2
J 0
(-7190 3655);
DISPLAY 0.489362 (-7190 3655);
FORCEPROP 1 LAST PACK_TYPE C0402
J 0
(-7150 3575);
DISPLAY 0.489362 (-7150 3575);
PAINT SKYBLUE (-7150 3575);
FORCEPROP 1 LAST VOLTAGE 4V
J 0
(-7150 3775);
DISPLAY 0.489362 (-7150 3775);
PAINT SKYBLUE (-7150 3775);
FORCEPROP 1 LAST VALUE 22UF
J 0
(-7150 3825);
DISPLAY 0.489362 (-7150 3825);
PAINT SKYBLUE (-7150 3825);
FORCEPROP 1 LAST TOLERANCE 20%
J 0
(-7150 3725);
DISPLAY 0.489362 (-7150 3725);
PAINT SKYBLUE (-7150 3725);
FORCEPROP 1 LAST MATERIAL X6S
J 0
(-7150 3675);
DISPLAY 0.489362 (-7150 3675);
PAINT SKYBLUE (-7150 3675);
FORCEPROP 2 LAST CDS_LIB pure_quanta
J 0
(-7200 3775);
PAINT MONO (-7200 3775);
DISPLAY INVISIBLE (-7200 3775);
FORCEPROP 1 LAST PATH I11
J 0
(-7150 3925);
DISPLAY 0.978723 (-7150 3925);
PAINT WHITE (-7150 3925);
DISPLAY INVISIBLE (-7150 3925);
FORCEPROP 1 LAST PART_NUMBER CH622KMEB02
J 0
(-7150 3625);
DISPLAY 0.489362 (-7150 3625);
PAINT SKYBLUE (-7150 3625);
DISPLAY INVISIBLE (-7150 3625);
FORCEADD Q_CAP..1
(-6750 3775);
FORCEPROP 1 LAST LOCATION C2668
J 0
(-6700 3875);
DISPLAY 0.489362 (-6700 3875);
PAINT SKYBLUE (-6700 3875);
FORCEPROP 2 LAST $SEC 1
J 0
(-6700 3975);
DISPLAY 0.680851 (-6700 3975);
PAINT MONO (-6700 3975);
DISPLAY INVISIBLE (-6700 3975);
FORCEPROP 2 LAST CDS_SEC 1
J 0
(-6700 3975);
DISPLAY 1.021277 (-6700 3975);
DISPLAY INVISIBLE (-6700 3975);
FORCEPROP 1 LASTPIN (-6750 3875) $PN 1
J 0
(-6740 3855);
DISPLAY 0.489362 (-6740 3855);
FORCEPROP 1 LASTPIN (-6750 3675) $PN 2
J 0
(-6740 3655);
DISPLAY 0.489362 (-6740 3655);
FORCEPROP 1 LAST PACK_TYPE C0402
J 0
(-6700 3575);
DISPLAY 0.489362 (-6700 3575);
PAINT SKYBLUE (-6700 3575);
FORCEPROP 1 LAST VOLTAGE 4V
J 0
(-6700 3775);
DISPLAY 0.489362 (-6700 3775);
PAINT SKYBLUE (-6700 3775);
FORCEPROP 1 LAST VALUE 22UF
J 0
(-6700 3825);
DISPLAY 0.489362 (-6700 3825);
PAINT SKYBLUE (-6700 3825);
FORCEPROP 1 LAST TOLERANCE 20%
J 0
(-6700 3725);
DISPLAY 0.489362 (-6700 3725);
PAINT SKYBLUE (-6700 3725);
FORCEPROP 1 LAST MATERIAL X6S
J 0
(-6700 3675);
DISPLAY 0.489362 (-6700 3675);
PAINT SKYBLUE (-6700 3675);
FORCEPROP 2 LAST CDS_LIB pure_quanta
J 0
(-6750 3775);
PAINT MONO (-6750 3775);
DISPLAY INVISIBLE (-6750 3775);
FORCEPROP 1 LAST PATH I12
J 0
(-6700 3925);
DISPLAY 0.978723 (-6700 3925);
PAINT WHITE (-6700 3925);
DISPLAY INVISIBLE (-6700 3925);
FORCEPROP 1 LAST PART_NUMBER CH622KMEB02
J 0
(-6700 3625);
DISPLAY 0.489362 (-6700 3625);
PAINT SKYBLUE (-6700 3625);
DISPLAY INVISIBLE (-6700 3625);
FORCEADD Q_CAP..1
(-6300 3775);
FORCEPROP 1 LAST LOCATION C2669
J 0
(-6250 3875);
DISPLAY 0.489362 (-6250 3875);
PAINT SKYBLUE (-6250 3875);
FORCEPROP 2 LAST $SEC 1
J 0
(-6250 3975);
DISPLAY 0.680851 (-6250 3975);
PAINT MONO (-6250 3975);
DISPLAY INVISIBLE (-6250 3975);
FORCEPROP 2 LAST CDS_SEC 1
J 0
(-6250 3975);
DISPLAY 1.021277 (-6250 3975);
DISPLAY INVISIBLE (-6250 3975);
FORCEPROP 1 LASTPIN (-6300 3875) $PN 1
J 0
(-6290 3855);
DISPLAY 0.489362 (-6290 3855);
FORCEPROP 1 LASTPIN (-6300 3675) $PN 2
J 0
(-6290 3655);
DISPLAY 0.489362 (-6290 3655);
FORCEPROP 1 LAST PACK_TYPE C0402
J 0
(-6250 3575);
DISPLAY 0.489362 (-6250 3575);
PAINT SKYBLUE (-6250 3575);
FORCEPROP 1 LAST VOLTAGE 4V
J 0
(-6250 3775);
DISPLAY 0.489362 (-6250 3775);
PAINT SKYBLUE (-6250 3775);
FORCEPROP 1 LAST VALUE 22UF
J 0
(-6250 3825);
DISPLAY 0.489362 (-6250 3825);
PAINT SKYBLUE (-6250 3825);
FORCEPROP 1 LAST TOLERANCE 20%
J 0
(-6250 3725);
DISPLAY 0.489362 (-6250 3725);
PAINT SKYBLUE (-6250 3725);
FORCEPROP 1 LAST MATERIAL X6S
J 0
(-6250 3675);
DISPLAY 0.489362 (-6250 3675);
PAINT SKYBLUE (-6250 3675);
FORCEPROP 2 LAST CDS_LIB pure_quanta
J 0
(-6300 3775);
PAINT MONO (-6300 3775);
DISPLAY INVISIBLE (-6300 3775);
FORCEPROP 1 LAST PATH I13
J 0
(-6250 3925);
DISPLAY 0.978723 (-6250 3925);
PAINT WHITE (-6250 3925);
DISPLAY INVISIBLE (-6250 3925);
FORCEPROP 1 LAST PART_NUMBER CH622KMEB02
J 0
(-6250 3625);
DISPLAY 0.489362 (-6250 3625);
PAINT SKYBLUE (-6250 3625);
DISPLAY INVISIBLE (-6250 3625);
FORCEADD Q_CAP..1
(-5850 3775);
FORCEPROP 1 LAST LOCATION C2670
J 0
(-5800 3875);
DISPLAY 0.489362 (-5800 3875);
PAINT SKYBLUE (-5800 3875);
FORCEPROP 2 LAST $SEC 1
J 0
(-5800 3975);
DISPLAY 0.680851 (-5800 3975);
PAINT MONO (-5800 3975);
DISPLAY INVISIBLE (-5800 3975);
FORCEPROP 2 LAST CDS_SEC 1
J 0
(-5800 3975);
DISPLAY 1.021277 (-5800 3975);
DISPLAY INVISIBLE (-5800 3975);
FORCEPROP 1 LASTPIN (-5850 3875) $PN 1
J 0
(-5840 3855);
DISPLAY 0.489362 (-5840 3855);
FORCEPROP 1 LASTPIN (-5850 3675) $PN 2
J 0
(-5840 3655);
DISPLAY 0.489362 (-5840 3655);
FORCEPROP 1 LAST PACK_TYPE C0402
J 0
(-5800 3575);
DISPLAY 0.489362 (-5800 3575);
PAINT SKYBLUE (-5800 3575);
FORCEPROP 1 LAST VOLTAGE 4V
J 0
(-5800 3775);
DISPLAY 0.489362 (-5800 3775);
PAINT SKYBLUE (-5800 3775);
FORCEPROP 1 LAST VALUE 22UF
J 0
(-5800 3825);
DISPLAY 0.489362 (-5800 3825);
PAINT SKYBLUE (-5800 3825);
FORCEPROP 1 LAST TOLERANCE 20%
J 0
(-5800 3725);
DISPLAY 0.489362 (-5800 3725);
PAINT SKYBLUE (-5800 3725);
FORCEPROP 1 LAST MATERIAL X6S
J 0
(-5800 3675);
DISPLAY 0.489362 (-5800 3675);
PAINT SKYBLUE (-5800 3675);
FORCEPROP 2 LAST CDS_LIB pure_quanta
J 0
(-5850 3775);
PAINT MONO (-5850 3775);
DISPLAY INVISIBLE (-5850 3775);
FORCEPROP 1 LAST PATH I14
J 0
(-5800 3925);
DISPLAY 0.978723 (-5800 3925);
PAINT WHITE (-5800 3925);
DISPLAY INVISIBLE (-5800 3925);
FORCEPROP 1 LAST PART_NUMBER CH622KMEB02
J 0
(-5800 3625);
DISPLAY 0.489362 (-5800 3625);
PAINT SKYBLUE (-5800 3625);
DISPLAY INVISIBLE (-5800 3625);
FORCEADD Q_CAP..1
(-5400 3775);
FORCEPROP 1 LAST LOCATION C2671
J 0
(-5350 3875);
DISPLAY 0.489362 (-5350 3875);
PAINT SKYBLUE (-5350 3875);
FORCEPROP 2 LAST $SEC 1
J 0
(-5350 3975);
DISPLAY 0.680851 (-5350 3975);
PAINT MONO (-5350 3975);
DISPLAY INVISIBLE (-5350 3975);
FORCEPROP 2 LAST CDS_SEC 1
J 0
(-5350 3975);
DISPLAY 1.021277 (-5350 3975);
DISPLAY INVISIBLE (-5350 3975);
FORCEPROP 1 LASTPIN (-5400 3875) $PN 1
J 0
(-5390 3855);
DISPLAY 0.489362 (-5390 3855);
FORCEPROP 1 LASTPIN (-5400 3675) $PN 2
J 0
(-5390 3655);
DISPLAY 0.489362 (-5390 3655);
FORCEPROP 1 LAST PACK_TYPE C0402
J 0
(-5350 3575);
DISPLAY 0.489362 (-5350 3575);
PAINT SKYBLUE (-5350 3575);
FORCEPROP 1 LAST VOLTAGE 4V
J 0
(-5350 3775);
DISPLAY 0.489362 (-5350 3775);
PAINT SKYBLUE (-5350 3775);
FORCEPROP 1 LAST VALUE 22UF
J 0
(-5350 3825);
DISPLAY 0.489362 (-5350 3825);
PAINT SKYBLUE (-5350 3825);
FORCEPROP 1 LAST TOLERANCE 20%
J 0
(-5350 3725);
DISPLAY 0.489362 (-5350 3725);
PAINT SKYBLUE (-5350 3725);
FORCEPROP 1 LAST MATERIAL X6S
J 0
(-5350 3675);
DISPLAY 0.489362 (-5350 3675);
PAINT SKYBLUE (-5350 3675);
FORCEPROP 2 LAST CDS_LIB pure_quanta
J 0
(-5400 3775);
PAINT MONO (-5400 3775);
DISPLAY INVISIBLE (-5400 3775);
FORCEPROP 1 LAST PATH I15
J 0
(-5350 3925);
DISPLAY 0.978723 (-5350 3925);
PAINT WHITE (-5350 3925);
DISPLAY INVISIBLE (-5350 3925);
FORCEPROP 1 LAST PART_NUMBER CH622KMEB02
J 0
(-5350 3625);
DISPLAY 0.489362 (-5350 3625);
PAINT SKYBLUE (-5350 3625);
DISPLAY INVISIBLE (-5350 3625);
FORCEADD Q_CAP..1
(-4950 3775);
FORCEPROP 1 LAST LOCATION C2672
J 0
(-4900 3875);
DISPLAY 0.489362 (-4900 3875);
PAINT SKYBLUE (-4900 3875);
FORCEPROP 2 LAST $SEC 1
J 0
(-4900 3975);
DISPLAY 0.680851 (-4900 3975);
PAINT MONO (-4900 3975);
DISPLAY INVISIBLE (-4900 3975);
FORCEPROP 2 LAST CDS_SEC 1
J 0
(-4900 3975);
DISPLAY 1.021277 (-4900 3975);
DISPLAY INVISIBLE (-4900 3975);
FORCEPROP 1 LASTPIN (-4950 3875) $PN 1
J 0
(-4940 3855);
DISPLAY 0.489362 (-4940 3855);
FORCEPROP 1 LASTPIN (-4950 3675) $PN 2
J 0
(-4940 3655);
DISPLAY 0.489362 (-4940 3655);
FORCEPROP 1 LAST PACK_TYPE C0402
J 0
(-4900 3575);
DISPLAY 0.489362 (-4900 3575);
PAINT SKYBLUE (-4900 3575);
FORCEPROP 1 LAST VOLTAGE 4V
J 0
(-4900 3775);
DISPLAY 0.489362 (-4900 3775);
PAINT SKYBLUE (-4900 3775);
FORCEPROP 1 LAST VALUE 22UF
J 0
(-4900 3825);
DISPLAY 0.489362 (-4900 3825);
PAINT SKYBLUE (-4900 3825);
FORCEPROP 1 LAST TOLERANCE 20%
J 0
(-4900 3725);
DISPLAY 0.489362 (-4900 3725);
PAINT SKYBLUE (-4900 3725);
FORCEPROP 1 LAST MATERIAL X6S
J 0
(-4900 3675);
DISPLAY 0.489362 (-4900 3675);
PAINT SKYBLUE (-4900 3675);
FORCEPROP 2 LAST CDS_LIB pure_quanta
J 0
(-4950 3775);
PAINT MONO (-4950 3775);
DISPLAY INVISIBLE (-4950 3775);
FORCEPROP 1 LAST PATH I16
J 0
(-4900 3925);
DISPLAY 0.978723 (-4900 3925);
PAINT WHITE (-4900 3925);
DISPLAY INVISIBLE (-4900 3925);
FORCEPROP 1 LAST PART_NUMBER CH622KMEB02
J 0
(-4900 3625);
DISPLAY 0.489362 (-4900 3625);
PAINT SKYBLUE (-4900 3625);
DISPLAY INVISIBLE (-4900 3625);
FORCEADD UNIVERSAL_GND..1
(-4550 3400);
FORCEPROP 3 LASTPIN (-4550 3450) SIG_NAME GND\g
J 0
(-4540 3460);
DISPLAY 0.659574 (-4540 3460);
PAINT MONO (-4540 3460);
DISPLAY INVISIBLE (-4540 3460);
FORCEPROP 2 LAST CDS_LIB pure_quanta_power
J 0
(-4550 3400);
PAINT MONO (-4550 3400);
DISPLAY INVISIBLE (-4550 3400);
FORCEPROP 1 LAST HDL_POWER GND
J 1
(-4525 3325);
DISPLAY 0.872340 (-4525 3325);
PAINT GREEN (-4525 3325);
DISPLAY INVISIBLE (-4525 3325);
FORCEPROP 1 LAST PATH I17
J 0
(-4475 3400);
DISPLAY 0.872340 (-4475 3400);
PAINT AQUA (-4475 3400);
DISPLAY INVISIBLE (-4475 3400);
FORCEADD Q_CAP..1
(-4550 3775);
FORCEPROP 1 LAST LOCATION C2673
J 0
(-4500 3875);
DISPLAY 0.489362 (-4500 3875);
PAINT SKYBLUE (-4500 3875);
FORCEPROP 2 LAST $SEC 1
J 0
(-4500 3975);
DISPLAY 0.680851 (-4500 3975);
PAINT MONO (-4500 3975);
DISPLAY INVISIBLE (-4500 3975);
FORCEPROP 2 LAST CDS_SEC 1
J 0
(-4500 3975);
DISPLAY 1.021277 (-4500 3975);
DISPLAY INVISIBLE (-4500 3975);
FORCEPROP 1 LASTPIN (-4550 3875) $PN 1
J 0
(-4540 3855);
DISPLAY 0.489362 (-4540 3855);
FORCEPROP 1 LASTPIN (-4550 3675) $PN 2
J 0
(-4540 3655);
DISPLAY 0.489362 (-4540 3655);
FORCEPROP 1 LAST PACK_TYPE C0402
J 0
(-4500 3575);
DISPLAY 0.489362 (-4500 3575);
PAINT SKYBLUE (-4500 3575);
FORCEPROP 1 LAST VOLTAGE 4V
J 0
(-4500 3775);
DISPLAY 0.489362 (-4500 3775);
PAINT SKYBLUE (-4500 3775);
FORCEPROP 1 LAST VALUE 22UF
J 0
(-4500 3825);
DISPLAY 0.489362 (-4500 3825);
PAINT SKYBLUE (-4500 3825);
FORCEPROP 1 LAST TOLERANCE 20%
J 0
(-4500 3725);
DISPLAY 0.489362 (-4500 3725);
PAINT SKYBLUE (-4500 3725);
FORCEPROP 1 LAST MATERIAL X6S
J 0
(-4500 3675);
DISPLAY 0.489362 (-4500 3675);
PAINT SKYBLUE (-4500 3675);
FORCEPROP 2 LAST CDS_LIB pure_quanta
J 0
(-4550 3775);
PAINT MONO (-4550 3775);
DISPLAY INVISIBLE (-4550 3775);
FORCEPROP 1 LAST PATH I18
J 0
(-4500 3925);
DISPLAY 0.978723 (-4500 3925);
PAINT WHITE (-4500 3925);
DISPLAY INVISIBLE (-4500 3925);
FORCEPROP 1 LAST PART_NUMBER CH622KMEB02
J 0
(-4500 3625);
DISPLAY 0.489362 (-4500 3625);
PAINT SKYBLUE (-4500 3625);
DISPLAY INVISIBLE (-4500 3625);
FORCEADD UNIVERSAL_POWER..1
(-8550 3275);
FORCEPROP 3 LASTPIN (-8550 3225) SIG_NAME PVDD18_S5_P1\g
J 0
(-8540 3235);
DISPLAY 0.659574 (-8540 3235);
PAINT MONO (-8540 3235);
DISPLAY INVISIBLE (-8540 3235);
FORCEPROP 1 LAST HDL_POWER PVDD18_S5_P1
J 1
(-8550 3325);
DISPLAY 0.489362 (-8550 3325);
PAINT GREEN (-8550 3325);
FORCEPROP 2 LAST CDS_LIB pure_quanta_power
J 0
(-8550 3275);
DISPLAY INVISIBLE (-8550 3275);
FORCEPROP 1 LAST PATH I2
J 0
(-8500 3300);
DISPLAY 0.872340 (-8500 3300);
PAINT AQUA (-8500 3300);
DISPLAY INVISIBLE (-8500 3300);
FORCEADD UNIVERSAL_POWER..1
(-8475 5675);
FORCEPROP 3 LASTPIN (-8475 5625) SIG_NAME PVDD_33_S5\g
J 0
(-8465 5635);
DISPLAY 0.659574 (-8465 5635);
PAINT MONO (-8465 5635);
DISPLAY INVISIBLE (-8465 5635);
FORCEPROP 1 LAST HDL_POWER PVDD_33_S5
J 1
(-8475 5725);
DISPLAY 0.489362 (-8475 5725);
PAINT GREEN (-8475 5725);
FORCEPROP 2 LAST CDS_LIB pure_quanta_power
J 0
(-8475 5675);
DISPLAY INVISIBLE (-8475 5675);
FORCEPROP 1 LAST PATH I23
J 0
(-8425 5700);
DISPLAY 0.872340 (-8425 5700);
PAINT AQUA (-8425 5700);
DISPLAY INVISIBLE (-8425 5700);
FORCEADD UNIVERSAL_GND..1
(-8025 5025);
FORCEPROP 3 LASTPIN (-8025 5075) SIG_NAME GND\g
J 0
(-8015 5085);
DISPLAY 0.659574 (-8015 5085);
PAINT MONO (-8015 5085);
DISPLAY INVISIBLE (-8015 5085);
FORCEPROP 2 LAST CDS_LIB pure_quanta_power
J 0
(-8025 5025);
PAINT MONO (-8025 5025);
DISPLAY INVISIBLE (-8025 5025);
FORCEPROP 1 LAST HDL_POWER GND
J 1
(-8000 4950);
DISPLAY 0.872340 (-8000 4950);
PAINT GREEN (-8000 4950);
DISPLAY INVISIBLE (-8000 4950);
FORCEPROP 1 LAST PATH I24
J 0
(-7950 5025);
DISPLAY 0.872340 (-7950 5025);
PAINT AQUA (-7950 5025);
DISPLAY INVISIBLE (-7950 5025);
FORCEADD Q_CAP..1
(-8025 5400);
FORCEPROP 1 LAST LOCATION C2662
J 0
(-7975 5500);
DISPLAY 0.638298 (-7975 5500);
FORCEPROP 0 LAST $SEC 1
J 0
(-7975 5550);
DISPLAY 0.680851 (-7975 5550);
PAINT MONO (-7975 5550);
DISPLAY INVISIBLE (-7975 5550);
FORCEPROP 0 LAST CDS_SEC 1
J 0
(-7975 5550);
DISPLAY 0.680851 (-7975 5550);
DISPLAY INVISIBLE (-7975 5550);
FORCEPROP 1 LASTPIN (-8025 5500) $PN 1
J 0
(-8015 5480);
DISPLAY 0.787234 (-8015 5480);
PAINT MONO (-8015 5480);
FORCEPROP 1 LASTPIN (-8025 5300) $PN 2
J 0
(-8015 5280);
DISPLAY 0.787234 (-8015 5280);
PAINT MONO (-8015 5280);
FORCEPROP 1 LAST PACK_TYPE C0402
J 0
(-7975 5200);
DISPLAY 0.638298 (-7975 5200);
FORCEPROP 1 LAST TOLERANCE 20%
J 0
(-7975 5350);
DISPLAY 0.638298 (-7975 5350);
FORCEPROP 1 LAST VALUE 10UF
J 0
(-7975 5450);
DISPLAY 0.638298 (-7975 5450);
FORCEPROP 1 LAST VOLTAGE 6.3V
J 0
(-7975 5400);
DISPLAY 0.638298 (-7975 5400);
FORCEPROP 1 LAST MATERIAL X6S
J 0
(-7975 5300);
DISPLAY 0.638298 (-7975 5300);
FORCEPROP 2 LAST CDS_LIB pure_quanta
J 0
(-8025 5400);
DISPLAY INVISIBLE (-8025 5400);
FORCEPROP 1 LAST PATH I25
J 0
(-7975 5550);
DISPLAY 0.978723 (-7975 5550);
PAINT WHITE (-7975 5550);
DISPLAY INVISIBLE (-7975 5550);
FORCEPROP 1 LAST PART_NUMBER CH6101MEB01
J 0
(-7975 5250);
DISPLAY 0.638298 (-7975 5250);
DISPLAY INVISIBLE (-7975 5250);
FORCEADD Q_CAP..1
(-8475 5400);
FORCEPROP 1 LAST LOCATION C2659
J 0
(-8425 5500);
DISPLAY 0.638298 (-8425 5500);
FORCEPROP 0 LAST $SEC 1
J 0
(-8425 5550);
DISPLAY 0.680851 (-8425 5550);
PAINT MONO (-8425 5550);
DISPLAY INVISIBLE (-8425 5550);
FORCEPROP 0 LAST CDS_SEC 1
J 0
(-8425 5550);
DISPLAY 0.680851 (-8425 5550);
DISPLAY INVISIBLE (-8425 5550);
FORCEPROP 1 LASTPIN (-8475 5500) $PN 1
J 0
(-8465 5480);
DISPLAY 0.787234 (-8465 5480);
PAINT MONO (-8465 5480);
FORCEPROP 1 LASTPIN (-8475 5300) $PN 2
J 0
(-8465 5280);
DISPLAY 0.787234 (-8465 5280);
PAINT MONO (-8465 5280);
FORCEPROP 1 LAST PACK_TYPE C0402
J 0
(-8425 5200);
DISPLAY 0.638298 (-8425 5200);
FORCEPROP 1 LAST TOLERANCE 20%
J 0
(-8425 5350);
DISPLAY 0.638298 (-8425 5350);
FORCEPROP 1 LAST VALUE 10UF
J 0
(-8425 5450);
DISPLAY 0.638298 (-8425 5450);
FORCEPROP 1 LAST VOLTAGE 6.3V
J 0
(-8425 5400);
DISPLAY 0.638298 (-8425 5400);
FORCEPROP 1 LAST MATERIAL X6S
J 0
(-8425 5300);
DISPLAY 0.638298 (-8425 5300);
FORCEPROP 2 LAST CDS_LIB pure_quanta
J 0
(-8475 5400);
DISPLAY INVISIBLE (-8475 5400);
FORCEPROP 1 LAST PATH I26
J 0
(-8425 5550);
DISPLAY 0.978723 (-8425 5550);
PAINT WHITE (-8425 5550);
DISPLAY INVISIBLE (-8425 5550);
FORCEPROP 1 LAST PART_NUMBER CH6101MEB01
J 0
(-8425 5250);
DISPLAY 0.638298 (-8425 5250);
DISPLAY INVISIBLE (-8425 5250);
FORCEADD Q_CAP..1
(-8550 3775);
FORCEPROP 1 LAST LOCATION C2660
J 0
(-8500 3875);
DISPLAY 0.489362 (-8500 3875);
PAINT SKYBLUE (-8500 3875);
FORCEPROP 2 LAST $SEC 1
J 0
(-8500 3975);
DISPLAY 0.680851 (-8500 3975);
PAINT MONO (-8500 3975);
DISPLAY INVISIBLE (-8500 3975);
FORCEPROP 2 LAST CDS_SEC 1
J 0
(-8500 3975);
DISPLAY 1.021277 (-8500 3975);
DISPLAY INVISIBLE (-8500 3975);
FORCEPROP 1 LASTPIN (-8550 3875) $PN 1
J 0
(-8540 3855);
DISPLAY 0.489362 (-8540 3855);
FORCEPROP 1 LASTPIN (-8550 3675) $PN 2
J 0
(-8540 3655);
DISPLAY 0.489362 (-8540 3655);
FORCEPROP 1 LAST PACK_TYPE C0402
J 0
(-8500 3575);
DISPLAY 0.489362 (-8500 3575);
PAINT SKYBLUE (-8500 3575);
FORCEPROP 1 LAST VOLTAGE 4V
J 0
(-8500 3775);
DISPLAY 0.489362 (-8500 3775);
PAINT SKYBLUE (-8500 3775);
FORCEPROP 1 LAST VALUE 22UF
J 0
(-8500 3825);
DISPLAY 0.489362 (-8500 3825);
PAINT SKYBLUE (-8500 3825);
FORCEPROP 1 LAST TOLERANCE 20%
J 0
(-8500 3725);
DISPLAY 0.489362 (-8500 3725);
PAINT SKYBLUE (-8500 3725);
FORCEPROP 1 LAST MATERIAL X6S
J 0
(-8500 3675);
DISPLAY 0.489362 (-8500 3675);
PAINT SKYBLUE (-8500 3675);
FORCEPROP 2 LAST CDS_LIB pure_quanta
J 0
(-8550 3775);
PAINT MONO (-8550 3775);
DISPLAY INVISIBLE (-8550 3775);
FORCEPROP 1 LAST PATH I3
J 0
(-8500 3925);
DISPLAY 0.978723 (-8500 3925);
PAINT WHITE (-8500 3925);
DISPLAY INVISIBLE (-8500 3925);
FORCEPROP 1 LAST PART_NUMBER CH622KMEB02
J 0
(-8500 3625);
DISPLAY 0.489362 (-8500 3625);
PAINT SKYBLUE (-8500 3625);
DISPLAY INVISIBLE (-8500 3625);
FORCEADD UNIVERSAL_POWER..1
(-8550 4050);
FORCEPROP 3 LASTPIN (-8550 4000) SIG_NAME PVDD18_S5_P1\g
J 0
(-8540 4010);
DISPLAY 0.659574 (-8540 4010);
PAINT MONO (-8540 4010);
DISPLAY INVISIBLE (-8540 4010);
FORCEPROP 1 LAST HDL_POWER PVDD18_S5_P1
J 1
(-8550 4100);
DISPLAY 0.489362 (-8550 4100);
PAINT GREEN (-8550 4100);
FORCEPROP 2 LAST CDS_LIB pure_quanta_power
J 0
(-8550 4050);
DISPLAY INVISIBLE (-8550 4050);
FORCEPROP 1 LAST PATH I4
J 0
(-8500 4075);
DISPLAY 0.872340 (-8500 4075);
PAINT AQUA (-8500 4075);
DISPLAY INVISIBLE (-8500 4075);
FORCEADD UNIVERSAL_GND..1
(-8100 2625);
FORCEPROP 3 LASTPIN (-8100 2675) SIG_NAME GND\g
J 0
(-8090 2685);
DISPLAY 0.659574 (-8090 2685);
PAINT MONO (-8090 2685);
DISPLAY INVISIBLE (-8090 2685);
FORCEPROP 2 LAST CDS_LIB pure_quanta_power
J 0
(-8100 2625);
DISPLAY INVISIBLE (-8100 2625);
FORCEPROP 1 LAST HDL_POWER GND
J 1
(-8075 2550);
DISPLAY 0.872340 (-8075 2550);
PAINT GREEN (-8075 2550);
DISPLAY INVISIBLE (-8075 2550);
FORCEPROP 1 LAST PATH I7
J 0
(-8025 2625);
DISPLAY 0.872340 (-8025 2625);
PAINT AQUA (-8025 2625);
DISPLAY INVISIBLE (-8025 2625);
FORCEADD Q_CAP..1
(-8100 3000);
FORCEPROP 1 LAST LOCATION C2664
J 0
(-8050 3100);
DISPLAY 0.489362 (-8050 3100);
PAINT SKYBLUE (-8050 3100);
FORCEPROP 2 LAST $SEC 1
J 0
(-8050 3200);
DISPLAY 0.680851 (-8050 3200);
PAINT MONO (-8050 3200);
DISPLAY INVISIBLE (-8050 3200);
FORCEPROP 2 LAST CDS_SEC 1
J 0
(-8050 3200);
DISPLAY 1.021277 (-8050 3200);
DISPLAY INVISIBLE (-8050 3200);
FORCEPROP 1 LASTPIN (-8100 3100) $PN 1
J 0
(-8090 3080);
DISPLAY 0.489362 (-8090 3080);
FORCEPROP 1 LASTPIN (-8100 2900) $PN 2
J 0
(-8090 2880);
DISPLAY 0.489362 (-8090 2880);
FORCEPROP 1 LAST PACK_TYPE C0402
J 0
(-8050 2800);
DISPLAY 0.489362 (-8050 2800);
PAINT SKYBLUE (-8050 2800);
FORCEPROP 1 LAST VOLTAGE 4V
J 0
(-8050 3000);
DISPLAY 0.489362 (-8050 3000);
PAINT SKYBLUE (-8050 3000);
FORCEPROP 1 LAST VALUE 22UF
J 0
(-8050 3050);
DISPLAY 0.489362 (-8050 3050);
PAINT SKYBLUE (-8050 3050);
FORCEPROP 1 LAST TOLERANCE 20%
J 0
(-8050 2950);
DISPLAY 0.489362 (-8050 2950);
PAINT SKYBLUE (-8050 2950);
FORCEPROP 1 LAST MATERIAL X6S
J 0
(-8050 2900);
DISPLAY 0.489362 (-8050 2900);
PAINT SKYBLUE (-8050 2900);
FORCEPROP 2 LAST CDS_LIB pure_quanta
J 0
(-8100 3000);
PAINT MONO (-8100 3000);
DISPLAY INVISIBLE (-8100 3000);
FORCEPROP 1 LAST PATH I8
J 0
(-8050 3150);
DISPLAY 0.978723 (-8050 3150);
PAINT WHITE (-8050 3150);
DISPLAY INVISIBLE (-8050 3150);
FORCEPROP 1 LAST PART_NUMBER CH622KMEB02
J 0
(-8050 2850);
DISPLAY 0.489362 (-8050 2850);
PAINT SKYBLUE (-8050 2850);
DISPLAY INVISIBLE (-8050 2850);
FORCEADD Q_CAP..1
(-8100 3775);
FORCEPROP 1 LAST LOCATION C2663
J 0
(-8050 3875);
DISPLAY 0.489362 (-8050 3875);
PAINT SKYBLUE (-8050 3875);
FORCEPROP 2 LAST $SEC 1
J 0
(-8050 3975);
DISPLAY 0.680851 (-8050 3975);
PAINT MONO (-8050 3975);
DISPLAY INVISIBLE (-8050 3975);
FORCEPROP 2 LAST CDS_SEC 1
J 0
(-8050 3975);
DISPLAY 1.021277 (-8050 3975);
DISPLAY INVISIBLE (-8050 3975);
FORCEPROP 1 LASTPIN (-8100 3875) $PN 1
J 0
(-8090 3855);
DISPLAY 0.489362 (-8090 3855);
FORCEPROP 1 LASTPIN (-8100 3675) $PN 2
J 0
(-8090 3655);
DISPLAY 0.489362 (-8090 3655);
FORCEPROP 1 LAST PACK_TYPE C0402
J 0
(-8050 3575);
DISPLAY 0.489362 (-8050 3575);
PAINT SKYBLUE (-8050 3575);
FORCEPROP 1 LAST VOLTAGE 4V
J 0
(-8050 3775);
DISPLAY 0.489362 (-8050 3775);
PAINT SKYBLUE (-8050 3775);
FORCEPROP 1 LAST VALUE 22UF
J 0
(-8050 3825);
DISPLAY 0.489362 (-8050 3825);
PAINT SKYBLUE (-8050 3825);
FORCEPROP 1 LAST TOLERANCE 20%
J 0
(-8050 3725);
DISPLAY 0.489362 (-8050 3725);
PAINT SKYBLUE (-8050 3725);
FORCEPROP 1 LAST MATERIAL X6S
J 0
(-8050 3675);
DISPLAY 0.489362 (-8050 3675);
PAINT SKYBLUE (-8050 3675);
FORCEPROP 2 LAST CDS_LIB pure_quanta
J 0
(-8100 3775);
PAINT MONO (-8100 3775);
DISPLAY INVISIBLE (-8100 3775);
FORCEPROP 1 LAST PATH I9
J 0
(-8050 3925);
DISPLAY 0.978723 (-8050 3925);
PAINT WHITE (-8050 3925);
DISPLAY INVISIBLE (-8050 3925);
FORCEPROP 1 LAST PART_NUMBER CH622KMEB02
J 0
(-8050 3625);
DISPLAY 0.489362 (-8050 3625);
PAINT SKYBLUE (-8050 3625);
DISPLAY INVISIBLE (-8050 3625);
FORCEADD QUANTA_TITLE_BLOCK_C..1
(0 0);
FORCEPROP 0 LAST CDS_CON_LAST_MODIFIED Thu Sep 14 16:12:04 2023
J 0
(-1885 15);
DISPLAY INVISIBLE (-1885 15);
FORCEPROP 1 LAST CUSTOM_TXT_CDS <CON_LAST_MODIFIED>
J 0
(-1885 15);
DISPLAY 0.978723 (-1885 15);
FORCEPROP 2 LAST CUSTOM_TXT_CDS <XR_PAGE_TITLE>
J 0
(-7890 5250);
DISPLAY 0.638298 (-7890 5250);
PAINT PINK (-7890 5250);
DISPLAY INVISIBLE (-7890 5250);
FORCEPROP 1 LAST CUSTOM_TXT_CDS <NAME_2>
J 0
(-3175 50);
FORCEPROP 1 LAST CUSTOM_TXT_CDS <NAME_1>
J 0
(-3175 175);
FORCEPROP 1 LAST CUSTOM_TXT_CDS <Q_NUMBER>
J 0
(-1403 103);
DISPLAY 1.212766 (-1403 103);
FORCEPROP 1 LAST CUSTOM_TXT_CDS <Q_PROJ>
J 0
(-2382 102);
DISPLAY 1.212766 (-2382 102);
FORCEPROP 1 LAST CUSTOM_TXT_CDS <Q_REV>
J 0
(-184 103);
DISPLAY 1.212766 (-184 103);
FORCEPROP 1 LAST CUSTOM_TXT_CDS <CON_PAGE_NUM> OF <CON_TOTAL_PAGES>
J 0
(-446 18);
DISPLAY 0.978723 (-446 18);
FORCEPROP 1 LAST Q_TITLE CPU1 CAVITY BOT DECOUPLING CAPS 3/3
J 0
(-9366 26);
DISPLAY 2.446809 (-9366 26);
PAINT GREEN (-9366 26);
FORCEPROP 2 LAST CDS_LIB pure_quanta
J 0
(0 0);
DISPLAY INVISIBLE (0 0);
FORCEPROP 1 LAST CDS_LMAN_SYM_OUTLINE -9475,6775,100,-125
J 0
(0 0);
DISPLAY 0.468085 (0 0);
PAINT GREEN (0 0);
DISPLAY INVISIBLE (0 0);
FORCEPROP 2 LAST PAGE_BORDER TRUE
J 0
(-7890 5250);
DISPLAY 0.638298 (-7890 5250);
PAINT PINK (-7890 5250);
DISPLAY INVISIBLE (-7890 5250);
FORCEPROP 2 LAST CDS_XR_PAGE_TITLE CR-75 : @T6G_MB_LIB.T6G(SCH_1):PAGE75
J 0
(-7890 5250);
DISPLAY 0.638298 (-7890 5250);
PAINT PINK (-7890 5250);
DISPLAY INVISIBLE (-7890 5250);
FORCEPROP 1 LAST Q_DEPT BU9
J 1
(-3763 49);
DISPLAY 1.957447 (-3763 49);
PAINT GREEN (-3763 49);
DISPLAY INVISIBLE (-3763 49);
FORCEPROP 1 LAST COMMENT_BODY TRUE
J 0
(12 -13);
DISPLAY 0.978723 (12 -13);
PAINT GREEN (12 -13);
DISPLAY INVISIBLE (12 -13);
WIRE 16 -1 (-8025 5500)(-8025 5575);
WIRE 16 -1 (-8025 5575)(-8475 5575);
WIRE 16 -1 (-8475 5575)(-8475 5625);
WIRE 16 -1 (-8475 5575)(-8475 5500);
WIRE 16 -1 (-8025 5175)(-8025 5300);
WIRE 16 -1 (-8025 5075)(-8025 5175);
WIRE 16 -1 (-8025 5175)(-8475 5175);
WIRE 16 -1 (-8475 5175)(-8475 5300);
WIRE 16 3135 (-8775 6175)(-4850 6175);
WIRE 16 3135 (-8775 4900)(-8775 6175);
WIRE 16 3135 (-4850 4900)(-4850 6175);
WIRE 16 3135 (-8775 4900)(-4850 4900);
WIRE 16 3135 (-8775 2475)(-4025 2475);
WIRE 16 3135 (-8775 2475)(-8775 4600);
WIRE 16 3135 (-4025 2475)(-4025 4600);
WIRE 16 3135 (-8775 4600)(-4025 4600);
WIRE 16 -1 (-8100 2775)(-8100 2900);
WIRE 16 -1 (-8100 2675)(-8100 2775);
WIRE 16 -1 (-8100 2775)(-8550 2775);
WIRE 16 -1 (-8550 2775)(-8550 2900);
WIRE 16 -1 (-7200 3950)(-7650 3950);
WIRE 16 -1 (-6750 3950)(-7200 3950);
WIRE 16 -1 (-7200 3875)(-7200 3950);
WIRE 16 -1 (-7650 3950)(-7650 3875);
WIRE 16 -1 (-7650 3950)(-8100 3950);
WIRE 16 -1 (-8100 3875)(-8100 3950);
WIRE 16 -1 (-8100 3950)(-8550 3950);
WIRE 16 -1 (-6300 3950)(-6750 3950);
WIRE 16 -1 (-6750 3875)(-6750 3950);
WIRE 16 -1 (-5850 3950)(-6300 3950);
WIRE 16 -1 (-6300 3950)(-6300 3875);
WIRE 16 -1 (-8550 3950)(-8550 4000);
WIRE 16 -1 (-8550 3950)(-8550 3875);
WIRE 16 -1 (-5400 3950)(-5850 3950);
WIRE 16 -1 (-5850 3875)(-5850 3950);
WIRE 16 -1 (-4950 3950)(-5400 3950);
WIRE 16 -1 (-5400 3875)(-5400 3950);
WIRE 16 -1 (-4550 3950)(-4950 3950);
WIRE 16 -1 (-4950 3950)(-4950 3875);
WIRE 16 -1 (-4550 3875)(-4550 3950);
WIRE 16 -1 (-8100 3100)(-8100 3175);
WIRE 16 -1 (-8100 3175)(-8550 3175);
WIRE 16 -1 (-8550 3175)(-8550 3225);
WIRE 16 -1 (-8550 3175)(-8550 3100);
WIRE 16 -1 (-7650 3550)(-8100 3550);
WIRE 16 -1 (-7650 3550)(-7650 3675);
WIRE 16 -1 (-7200 3550)(-7650 3550);
WIRE 16 -1 (-8100 3550)(-8100 3675);
WIRE 16 -1 (-8100 3550)(-8550 3550);
WIRE 16 -1 (-8550 3550)(-8550 3675);
WIRE 16 -1 (-6750 3550)(-7200 3550);
WIRE 16 -1 (-7200 3550)(-7200 3675);
WIRE 16 -1 (-6300 3550)(-6750 3550);
WIRE 16 -1 (-6750 3550)(-6750 3675);
WIRE 16 -1 (-5850 3550)(-6300 3550);
WIRE 16 -1 (-6300 3550)(-6300 3675);
WIRE 16 -1 (-5400 3550)(-5850 3550);
WIRE 16 -1 (-5850 3550)(-5850 3675);
WIRE 16 -1 (-4950 3550)(-5400 3550);
WIRE 16 -1 (-5400 3550)(-5400 3675);
WIRE 16 -1 (-4550 3550)(-4950 3550);
WIRE 16 -1 (-4950 3550)(-4950 3675);
WIRE 16 -1 (-4550 3550)(-4550 3675);
WIRE 16 -1 (-4550 3450)(-4550 3550);
DOT 1 (-8475 5575);
DOT 1 (-8025 5175);
DOT 1 (-5400 3950);
DOT 1 (-4550 3550);
DOT 1 (-4950 3950);
DOT 1 (-4950 3550);
DOT 1 (-5400 3550);
DOT 1 (-5850 3950);
DOT 1 (-5850 3550);
DOT 1 (-6300 3950);
DOT 1 (-6300 3550);
DOT 1 (-6750 3950);
DOT 1 (-7200 3950);
DOT 1 (-7200 3550);
DOT 1 (-6750 3550);
DOT 1 (-7650 3950);
DOT 1 (-7650 3550);
DOT 1 (-8100 3950);
DOT 1 (-8100 3550);
DOT 1 (-8100 2775);
DOT 1 (-8550 3950);
DOT 1 (-8550 3175);
FORCENOTE
PVDD33_S5: 2PCS 22UF ON BOT
(-8575 5900) 0;
DISPLAY LEFT (-8575 5900);
DISPLAY 2.510638 (-8575 5900);
PAINT WHITE (-8575 5900);
FORCENOTE
PVDD18_S5_P1: 12PCS 22UF ON BOT
(-8625 4375) 0;
DISPLAY LEFT (-8625 4375);
DISPLAY 2.510638 (-8625 4375);
PAINT WHITE (-8625 4375);
FORCENOTE
10
(-4600 4025) 0;
DISPLAY LEFT (-4600 4025);
DISPLAY 1.021277 (-4600 4025);
PAINT SKYBLUE (-4600 4025);
FORCENOTE
5
(-6775 4025) 0;
DISPLAY LEFT (-6775 4025);
DISPLAY 1.021277 (-6775 4025);
PAINT SKYBLUE (-6775 4025);
QUIT
